(kicad_pcb
	(version 20260206)
	(generator "pcbnew")
	(generator_version "10.0")
	(general
		(thickness 1.6)
		(legacy_teardrops no)
	)
	(paper "A4")
	(title_block
		(title "04192023_DAF0TMB3IC0_F0TG_MB_C_brd_V02_OCP.brd")
		(comment 1 "Grand Teton / footprints 4189-4195 of 8354")
	)
	(layers
		(0 "F.Cu" signal "TOP")
		(4 "In1.Cu" signal "GND")
		(6 "In2.Cu" signal "IN1")
		(8 "In3.Cu" signal "GND1")
		(10 "In4.Cu" signal "IN2")
		(12 "In5.Cu" signal "GND2")
		(14 "In6.Cu" signal "IN3")
		(16 "In7.Cu" signal "GND3")
		(18 "In8.Cu" signal "VCC")
		(20 "In9.Cu" signal "VCC1")
		(22 "In10.Cu" signal "GND4")
		(24 "In11.Cu" signal "IN4")
		(26 "In12.Cu" signal "GND5")
		(28 "In13.Cu" signal "IN5")
		(30 "In14.Cu" signal "GND6")
		(32 "In15.Cu" signal "IN6")
		(34 "In16.Cu" signal "GND7")
		(2 "B.Cu" signal "BOTTOM")
		(9 "F.Adhes" user "F.Adhesive")
		(11 "B.Adhes" user "B.Adhesive")
		(13 "F.Paste" user "Package Geometry/Pastemask Top")
		(15 "B.Paste" user "Package Geometry/Pastemask Bottom")
		(5 "F.SilkS" user "Ref Des/Silkscreen Top")
		(7 "B.SilkS" user "Ref Des/Silkscreen Bottom")
		(1 "F.Mask" user "Board Geometry/Soldermask Top")
		(3 "B.Mask" user "Board Geometry/Soldermask Bottom")
		(17 "Dwgs.User" user "User.Drawings")
		(19 "Cmts.User" user "User.Comments")
		(21 "Eco1.User" user "User.Eco1")
		(23 "Eco2.User" user "User.Eco2")
		(25 "Edge.Cuts" user "Board Geometry/Outline")
		(27 "Margin" user)
		(31 "F.CrtYd" user "Package Geometry/Place Bound Top")
		(29 "B.CrtYd" user "Package Geometry/Place Bound Bottom")
		(35 "F.Fab" user "Ref Des/Assembly Top")
		(33 "B.Fab" user "Ref Des/Assembly Bottom")
	)
	(footprint ""
		(layer "F.Cu")
		(at 201.082148 -122.798332)
		(property "Reference" "R3324"
			(at 0 0 0)
			(layer "F.SilkS")
			(hide yes)
			(effects
				(font
					(size 1.27 1.27)
				)
			)
		)
		(property "Value" ""
			(at 0 0 0)
			(layer "F.Fab")
			(effects
				(font
					(size 1.27 1.27)
				)
			)
		)
		(duplicate_pad_numbers_are_jumpers no)
		(fp_line
			(start -0.7874 -0.4064)
			(end 0.7874 -0.4064)
			(stroke
				(width 0.1524)
				(type default)
			)
			(layer "F.SilkS")
		)
		(fp_line
			(start -0.7874 0.4064)
			(end -0.7874 -0.4064)
			(stroke
				(width 0.1524)
				(type default)
			)
			(layer "F.SilkS")
		)
		(fp_line
			(start 0.7874 -0.4064)
			(end 0.7874 0.4064)
			(stroke
				(width 0.1524)
				(type default)
			)
			(layer "F.SilkS")
		)
		(fp_line
			(start 0.7874 0.4064)
			(end -0.7874 0.4064)
			(stroke
				(width 0.1524)
				(type default)
			)
			(layer "F.SilkS")
		)
		(fp_line
			(start -0.67945 -0.305054)
			(end -0.12065 -0.305054)
			(stroke
				(width 0.1)
				(type default)
			)
			(layer "F.Fab")
		)
		(fp_line
			(start -0.67945 0.3048)
			(end -0.67945 -0.305054)
			(stroke
				(width 0.1)
				(type default)
			)
			(layer "F.Fab")
		)
		(fp_line
			(start -0.12065 -0.305054)
			(end -0.12065 -0.2794)
			(stroke
				(width 0.1)
				(type default)
			)
			(layer "F.Fab")
		)
		(fp_line
			(start -0.12065 -0.2794)
			(end 0.12065 -0.2794)
			(stroke
				(width 0.1)
				(type default)
			)
			(layer "F.Fab")
		)
		(fp_line
			(start -0.12065 0.2794)
			(end -0.12065 0.3048)
			(stroke
				(width 0.1)
				(type default)
			)
			(layer "F.Fab")
		)
		(fp_line
			(start -0.12065 0.3048)
			(end -0.67945 0.3048)
			(stroke
				(width 0.1)
				(type default)
			)
			(layer "F.Fab")
		)
		(fp_line
			(start 0.120396 0.2794)
			(end -0.12065 0.2794)
			(stroke
				(width 0.1)
				(type default)
			)
			(layer "F.Fab")
		)
		(fp_line
			(start 0.120396 0.3048)
			(end 0.120396 0.2794)
			(stroke
				(width 0.1)
				(type default)
			)
			(layer "F.Fab")
		)
		(fp_line
			(start 0.12065 -0.3048)
			(end 0.67945 -0.3048)
			(stroke
				(width 0.1)
				(type default)
			)
			(layer "F.Fab")
		)
		(fp_line
			(start 0.12065 -0.2794)
			(end 0.12065 -0.3048)
			(stroke
				(width 0.1)
				(type default)
			)
			(layer "F.Fab")
		)
		(fp_line
			(start 0.67945 -0.3048)
			(end 0.67945 0.3048)
			(stroke
				(width 0.1)
				(type default)
			)
			(layer "F.Fab")
		)
		(fp_line
			(start 0.67945 0.3048)
			(end 0.120396 0.3048)
			(stroke
				(width 0.1)
				(type default)
			)
			(layer "F.Fab")
		)
		(pad "1" smd circle
			(at -0.40005 0)
			(size 0 0)
			(layers "F.Cu" "F.Mask" "F.Paste")
			(net "GPU_FPGA_READY_ISO_R")
		)
		(pad "2" smd circle
			(at 0.40005 0)
			(size 0 0)
			(layers "F.Cu" "F.Mask" "F.Paste")
			(net "GPU_FPGA_READY_ISO")
		)
	)
	(footprint ""
		(layer "F.Cu")
		(at 81.525364 -178.0921 -90)
		(property "Reference" "PR189"
			(at 0 0 270)
			(layer "F.SilkS")
			(hide yes)
			(effects
				(font
					(size 1.27 1.27)
				)
			)
		)
		(property "Value" ""
			(at 0 0 270)
			(layer "F.Fab")
			(effects
				(font
					(size 1.27 1.27)
				)
			)
		)
		(duplicate_pad_numbers_are_jumpers no)
		(fp_line
			(start -0.7874 0.4064)
			(end -0.7874 -0.4064)
			(stroke
				(width 0.1524)
				(type default)
			)
			(layer "F.SilkS")
		)
		(fp_line
			(start 0.7874 0.4064)
			(end -0.7874 0.4064)
			(stroke
				(width 0.1524)
				(type default)
			)
			(layer "F.SilkS")
		)
		(fp_line
			(start -0.7874 -0.4064)
			(end 0.7874 -0.4064)
			(stroke
				(width 0.1524)
				(type default)
			)
			(layer "F.SilkS")
		)
		(fp_line
			(start 0.7874 -0.4064)
			(end 0.7874 0.4064)
			(stroke
				(width 0.1524)
				(type default)
			)
			(layer "F.SilkS")
		)
		(fp_line
			(start -0.67945 0.3048)
			(end -0.67945 -0.305054)
			(stroke
				(width 0.1)
				(type default)
			)
			(layer "F.Fab")
		)
		(fp_line
			(start -0.12065 0.3048)
			(end -0.67945 0.3048)
			(stroke
				(width 0.1)
				(type default)
			)
			(layer "F.Fab")
		)
		(fp_line
			(start 0.120396 0.3048)
			(end 0.120396 0.2794)
			(stroke
				(width 0.1)
				(type default)
			)
			(layer "F.Fab")
		)
		(fp_line
			(start 0.67945 0.3048)
			(end 0.120396 0.3048)
			(stroke
				(width 0.1)
				(type default)
			)
			(layer "F.Fab")
		)
		(fp_line
			(start -0.12065 0.2794)
			(end -0.12065 0.3048)
			(stroke
				(width 0.1)
				(type default)
			)
			(layer "F.Fab")
		)
		(fp_line
			(start 0.120396 0.2794)
			(end -0.12065 0.2794)
			(stroke
				(width 0.1)
				(type default)
			)
			(layer "F.Fab")
		)
		(fp_line
			(start -0.12065 -0.2794)
			(end 0.12065 -0.2794)
			(stroke
				(width 0.1)
				(type default)
			)
			(layer "F.Fab")
		)
		(fp_line
			(start 0.12065 -0.2794)
			(end 0.12065 -0.3048)
			(stroke
				(width 0.1)
				(type default)
			)
			(layer "F.Fab")
		)
		(fp_line
			(start 0.12065 -0.3048)
			(end 0.67945 -0.3048)
			(stroke
				(width 0.1)
				(type default)
			)
			(layer "F.Fab")
		)
		(fp_line
			(start 0.67945 -0.3048)
			(end 0.67945 0.3048)
			(stroke
				(width 0.1)
				(type default)
			)
			(layer "F.Fab")
		)
		(fp_line
			(start -0.67945 -0.305054)
			(end -0.12065 -0.305054)
			(stroke
				(width 0.1)
				(type default)
			)
			(layer "F.Fab")
		)
		(fp_line
			(start -0.12065 -0.305054)
			(end -0.12065 -0.2794)
			(stroke
				(width 0.1)
				(type default)
			)
			(layer "F.Fab")
		)
		(pad "1" smd circle
			(at -0.40005 0 270)
			(size 0 0)
			(layers "F.Cu" "F.Mask" "F.Paste")
			(net "SW_PVDDCR_CPU0_P1_BOOT1")
		)
		(pad "2" smd circle
			(at 0.40005 0 270)
			(size 0 0)
			(layers "F.Cu" "F.Mask" "F.Paste")
			(net "SW_PVDDCR_CPU0_P1_BOOT1_RC")
		)
	)
	(footprint ""
		(layer "F.Cu")
		(at 110.067344 -376.85726 180)
		(property "Reference" "C1544"
			(at 0 0 180)
			(layer "F.SilkS")
			(hide yes)
			(effects
				(font
					(size 1.27 1.27)
				)
			)
		)
		(property "Value" ""
			(at 0 0 180)
			(layer "F.Fab")
			(effects
				(font
					(size 1.27 1.27)
				)
			)
		)
		(duplicate_pad_numbers_are_jumpers no)
		(fp_line
			(start 0.299974 0.150114)
			(end -0.299974 0.150114)
			(stroke
				(width 0.1)
				(type default)
			)
			(layer "F.Fab")
		)
		(fp_line
			(start 0.299974 -0.150114)
			(end 0.299974 0.150114)
			(stroke
				(width 0.1)
				(type default)
			)
			(layer "F.Fab")
		)
		(fp_line
			(start -0.299974 0.150114)
			(end -0.299974 -0.150114)
			(stroke
				(width 0.1)
				(type default)
			)
			(layer "F.Fab")
		)
		(fp_line
			(start -0.299974 -0.150114)
			(end 0.299974 -0.150114)
			(stroke
				(width 0.1)
				(type default)
			)
			(layer "F.Fab")
		)
		(pad "1" smd rect
			(at -0.2667 0 180)
			(size 0.3048 0.381)
			(layers "F.Cu" "F.Mask" "F.Paste")
			(net "P5E_CPU1_P3_TX_C_DN<1>")
		)
		(pad "2" smd rect
			(at 0.2667 0 180)
			(size 0.3048 0.381)
			(layers "F.Cu" "F.Mask" "F.Paste")
			(net "P5E_CPU1_P3_TX_DN<1>")
		)
	)
	(footprint ""
		(layer "F.Cu")
		(at 215.4301 -407.068782 180)
		(property "Reference" "PR3912"
			(at 0 0 180)
			(layer "F.SilkS")
			(hide yes)
			(effects
				(font
					(size 1.27 1.27)
				)
			)
		)
		(property "Value" ""
			(at 0 0 180)
			(layer "F.Fab")
			(effects
				(font
					(size 1.27 1.27)
				)
			)
		)
		(duplicate_pad_numbers_are_jumpers no)
		(fp_line
			(start 0.7874 0.4064)
			(end -0.7874 0.4064)
			(stroke
				(width 0.1524)
				(type default)
			)
			(layer "F.SilkS")
		)
		(fp_line
			(start 0.7874 -0.4064)
			(end 0.7874 0.4064)
			(stroke
				(width 0.1524)
				(type default)
			)
			(layer "F.SilkS")
		)
		(fp_line
			(start -0.7874 0.4064)
			(end -0.7874 -0.4064)
			(stroke
				(width 0.1524)
				(type default)
			)
			(layer "F.SilkS")
		)
		(fp_line
			(start -0.7874 -0.4064)
			(end 0.7874 -0.4064)
			(stroke
				(width 0.1524)
				(type default)
			)
			(layer "F.SilkS")
		)
		(fp_line
			(start 0.67945 0.3048)
			(end 0.120396 0.3048)
			(stroke
				(width 0.1)
				(type default)
			)
			(layer "F.Fab")
		)
		(fp_line
			(start 0.67945 -0.3048)
			(end 0.67945 0.3048)
			(stroke
				(width 0.1)
				(type default)
			)
			(layer "F.Fab")
		)
		(fp_line
			(start 0.12065 -0.2794)
			(end 0.12065 -0.3048)
			(stroke
				(width 0.1)
				(type default)
			)
			(layer "F.Fab")
		)
		(fp_line
			(start 0.12065 -0.3048)
			(end 0.67945 -0.3048)
			(stroke
				(width 0.1)
				(type default)
			)
			(layer "F.Fab")
		)
		(fp_line
			(start 0.120396 0.3048)
			(end 0.120396 0.2794)
			(stroke
				(width 0.1)
				(type default)
			)
			(layer "F.Fab")
		)
		(fp_line
			(start 0.120396 0.2794)
			(end -0.12065 0.2794)
			(stroke
				(width 0.1)
				(type default)
			)
			(layer "F.Fab")
		)
		(fp_line
			(start -0.12065 0.3048)
			(end -0.67945 0.3048)
			(stroke
				(width 0.1)
				(type default)
			)
			(layer "F.Fab")
		)
		(fp_line
			(start -0.12065 0.2794)
			(end -0.12065 0.3048)
			(stroke
				(width 0.1)
				(type default)
			)
			(layer "F.Fab")
		)
		(fp_line
			(start -0.12065 -0.2794)
			(end 0.12065 -0.2794)
			(stroke
				(width 0.1)
				(type default)
			)
			(layer "F.Fab")
		)
		(fp_line
			(start -0.12065 -0.305054)
			(end -0.12065 -0.2794)
			(stroke
				(width 0.1)
				(type default)
			)
			(layer "F.Fab")
		)
		(fp_line
			(start -0.67945 0.3048)
			(end -0.67945 -0.305054)
			(stroke
				(width 0.1)
				(type default)
			)
			(layer "F.Fab")
		)
		(fp_line
			(start -0.67945 -0.305054)
			(end -0.12065 -0.305054)
			(stroke
				(width 0.1)
				(type default)
			)
			(layer "F.Fab")
		)
		(pad "1" smd circle
			(at -0.40005 0 180)
			(size 0 0)
			(layers "F.Cu" "F.Mask" "F.Paste")
			(net "AGND_HSC")
		)
		(pad "2" smd circle
			(at 0.40005 0 180)
			(size 0 0)
			(layers "F.Cu" "F.Mask" "F.Paste")
			(net "HSC_MODE_2")
		)
	)
	(footprint ""
		(layer "F.Cu")
		(at 297.486324 -112.354614 180)
		(property "Reference" "R2985"
			(at 0 0 180)
			(layer "F.SilkS")
			(hide yes)
			(effects
				(font
					(size 1.27 1.27)
				)
			)
		)
		(property "Value" ""
			(at 0 0 180)
			(layer "F.Fab")
			(effects
				(font
					(size 1.27 1.27)
				)
			)
		)
		(duplicate_pad_numbers_are_jumpers no)
		(fp_line
			(start 0.7874 0.4064)
			(end -0.7874 0.4064)
			(stroke
				(width 0.1524)
				(type default)
			)
			(layer "F.SilkS")
		)
		(fp_line
			(start 0.7874 -0.4064)
			(end 0.7874 0.4064)
			(stroke
				(width 0.1524)
				(type default)
			)
			(layer "F.SilkS")
		)
		(fp_line
			(start -0.7874 0.4064)
			(end -0.7874 -0.4064)
			(stroke
				(width 0.1524)
				(type default)
			)
			(layer "F.SilkS")
		)
		(fp_line
			(start -0.7874 -0.4064)
			(end 0.7874 -0.4064)
			(stroke
				(width 0.1524)
				(type default)
			)
			(layer "F.SilkS")
		)
		(fp_line
			(start 0.67945 0.3048)
			(end 0.120396 0.3048)
			(stroke
				(width 0.1)
				(type default)
			)
			(layer "F.Fab")
		)
		(fp_line
			(start 0.67945 -0.3048)
			(end 0.67945 0.3048)
			(stroke
				(width 0.1)
				(type default)
			)
			(layer "F.Fab")
		)
		(fp_line
			(start 0.12065 -0.2794)
			(end 0.12065 -0.3048)
			(stroke
				(width 0.1)
				(type default)
			)
			(layer "F.Fab")
		)
		(fp_line
			(start 0.12065 -0.3048)
			(end 0.67945 -0.3048)
			(stroke
				(width 0.1)
				(type default)
			)
			(layer "F.Fab")
		)
		(fp_line
			(start 0.120396 0.3048)
			(end 0.120396 0.2794)
			(stroke
				(width 0.1)
				(type default)
			)
			(layer "F.Fab")
		)
		(fp_line
			(start 0.120396 0.2794)
			(end -0.12065 0.2794)
			(stroke
				(width 0.1)
				(type default)
			)
			(layer "F.Fab")
		)
		(fp_line
			(start -0.12065 0.3048)
			(end -0.67945 0.3048)
			(stroke
				(width 0.1)
				(type default)
			)
			(layer "F.Fab")
		)
		(fp_line
			(start -0.12065 0.2794)
			(end -0.12065 0.3048)
			(stroke
				(width 0.1)
				(type default)
			)
			(layer "F.Fab")
		)
		(fp_line
			(start -0.12065 -0.2794)
			(end 0.12065 -0.2794)
			(stroke
				(width 0.1)
				(type default)
			)
			(layer "F.Fab")
		)
		(fp_line
			(start -0.12065 -0.305054)
			(end -0.12065 -0.2794)
			(stroke
				(width 0.1)
				(type default)
			)
			(layer "F.Fab")
		)
		(fp_line
			(start -0.67945 0.3048)
			(end -0.67945 -0.305054)
			(stroke
				(width 0.1)
				(type default)
			)
			(layer "F.Fab")
		)
		(fp_line
			(start -0.67945 -0.305054)
			(end -0.12065 -0.305054)
			(stroke
				(width 0.1)
				(type default)
			)
			(layer "F.Fab")
		)
		(pad "1" smd circle
			(at -0.40005 0 180)
			(size 0 0)
			(layers "F.Cu" "F.Mask" "F.Paste")
			(net "P3V3_AUX")
		)
		(pad "2" smd circle
			(at 0.40005 0 180)
			(size 0 0)
			(layers "F.Cu" "F.Mask" "F.Paste")
			(net "SMB_BMC_SWB_SDA")
		)
	)
	(footprint ""
		(layer "F.Cu")
		(at 16.162782 -404.341584 90)
		(property "Reference" "R657"
			(at 0 0 90)
			(layer "F.SilkS")
			(hide yes)
			(effects
				(font
					(size 1.27 1.27)
				)
			)
		)
		(property "Value" ""
			(at 0 0 90)
			(layer "F.Fab")
			(effects
				(font
					(size 1.27 1.27)
				)
			)
		)
		(duplicate_pad_numbers_are_jumpers no)
		(fp_line
			(start 0.7874 -0.4064)
			(end 0.7874 0.4064)
			(stroke
				(width 0.1524)
				(type default)
			)
			(layer "F.SilkS")
		)
		(fp_line
			(start -0.7874 -0.4064)
			(end 0.7874 -0.4064)
			(stroke
				(width 0.1524)
				(type default)
			)
			(layer "F.SilkS")
		)
		(fp_line
			(start 0.7874 0.4064)
			(end -0.7874 0.4064)
			(stroke
				(width 0.1524)
				(type default)
			)
			(layer "F.SilkS")
		)
		(fp_line
			(start -0.7874 0.4064)
			(end -0.7874 -0.4064)
			(stroke
				(width 0.1524)
				(type default)
			)
			(layer "F.SilkS")
		)
		(fp_line
			(start -0.12065 -0.305054)
			(end -0.12065 -0.2794)
			(stroke
				(width 0.1)
				(type default)
			)
			(layer "F.Fab")
		)
		(fp_line
			(start -0.67945 -0.305054)
			(end -0.12065 -0.305054)
			(stroke
				(width 0.1)
				(type default)
			)
			(layer "F.Fab")
		)
		(fp_line
			(start 0.67945 -0.3048)
			(end 0.67945 0.3048)
			(stroke
				(width 0.1)
				(type default)
			)
			(layer "F.Fab")
		)
		(fp_line
			(start 0.12065 -0.3048)
			(end 0.67945 -0.3048)
			(stroke
				(width 0.1)
				(type default)
			)
			(layer "F.Fab")
		)
		(fp_line
			(start 0.12065 -0.2794)
			(end 0.12065 -0.3048)
			(stroke
				(width 0.1)
				(type default)
			)
			(layer "F.Fab")
		)
		(fp_line
			(start -0.12065 -0.2794)
			(end 0.12065 -0.2794)
			(stroke
				(width 0.1)
				(type default)
			)
			(layer "F.Fab")
		)
		(fp_line
			(start 0.120396 0.2794)
			(end -0.12065 0.2794)
			(stroke
				(width 0.1)
				(type default)
			)
			(layer "F.Fab")
		)
		(fp_line
			(start -0.12065 0.2794)
			(end -0.12065 0.3048)
			(stroke
				(width 0.1)
				(type default)
			)
			(layer "F.Fab")
		)
		(fp_line
			(start 0.67945 0.3048)
			(end 0.120396 0.3048)
			(stroke
				(width 0.1)
				(type default)
			)
			(layer "F.Fab")
		)
		(fp_line
			(start 0.120396 0.3048)
			(end 0.120396 0.2794)
			(stroke
				(width 0.1)
				(type default)
			)
			(layer "F.Fab")
		)
		(fp_line
			(start -0.12065 0.3048)
			(end -0.67945 0.3048)
			(stroke
				(width 0.1)
				(type default)
			)
			(layer "F.Fab")
		)
		(fp_line
			(start -0.67945 0.3048)
			(end -0.67945 -0.305054)
			(stroke
				(width 0.1)
				(type default)
			)
			(layer "F.Fab")
		)
		(pad "1" smd circle
			(at -0.40005 0 90)
			(size 0 0)
			(layers "F.Cu" "F.Mask" "F.Paste")
			(net "P0V9_RETIMER_CPU1_PMSCL")
		)
		(pad "2" smd circle
			(at 0.40005 0 90)
			(size 0 0)
			(layers "F.Cu" "F.Mask" "F.Paste")
			(net "P0V9_RETIMER_CPU1_PMSCL_R")
		)
	)
	(footprint ""
		(layer "F.Cu")
		(at 350.237044 -383.88163 -90)
		(property "Reference" "C945"
			(at 0 0 270)
			(layer "F.SilkS")
			(hide yes)
			(effects
				(font
					(size 1.27 1.27)
				)
			)
		)
		(property "Value" ""
			(at 0 0 270)
			(layer "F.Fab")
			(effects
				(font
					(size 1.27 1.27)
				)
			)
		)
		(duplicate_pad_numbers_are_jumpers no)
		(fp_line
			(start -0.299974 0.150114)
			(end -0.299974 -0.150114)
			(stroke
				(width 0.1)
				(type default)
			)
			(layer "F.Fab")
		)
		(fp_line
			(start 0.299974 0.150114)
			(end -0.299974 0.150114)
			(stroke
				(width 0.1)
				(type default)
			)
			(layer "F.Fab")
		)
		(fp_line
			(start -0.299974 -0.150114)
			(end 0.299974 -0.150114)
			(stroke
				(width 0.1)
				(type default)
			)
			(layer "F.Fab")
		)
		(fp_line
			(start 0.299974 -0.150114)
			(end 0.299974 0.150114)
			(stroke
				(width 0.1)
				(type default)
			)
			(layer "F.Fab")
		)
		(pad "1" smd rect
			(at -0.2667 0 270)
			(size 0.3048 0.381)
			(layers "F.Cu" "F.Mask" "F.Paste")
			(net "P5E_CPU0_P1_TX_C_DP<10>")
		)
		(pad "2" smd rect
			(at 0.2667 0 270)
			(size 0.3048 0.381)
			(layers "F.Cu" "F.Mask" "F.Paste")
			(net "P5E_CPU0_P1_TX_DP<10>")
		)
	)
)
